(kicad_pcb
	(version 20260206)
	(generator "pcbnew")
	(generator_version "10.0")
	(general
		(thickness 1.6)
		(legacy_teardrops no)
	)
	(paper "A4")
	(title_block
		(title "12092022_DA0F0TYB4D0_F0T_Panel_BD_Front_D_brd_v02_OCP.brd")
		(comment 1 "Grand Teton / footprints 99-104 of 128")
	)
	(layers
		(0 "F.Cu" signal "TOP")
		(4 "In1.Cu" signal "GND")
		(6 "In2.Cu" signal "GND1")
		(2 "B.Cu" signal "BOTTOM")
		(9 "F.Adhes" user "F.Adhesive")
		(11 "B.Adhes" user "B.Adhesive")
		(13 "F.Paste" user "Package Geometry/Pastemask Top")
		(15 "B.Paste" user "Package Geometry/Pastemask Bottom")
		(5 "F.SilkS" user "Ref Des/Silkscreen Top")
		(7 "B.SilkS" user "Ref Des/Silkscreen Bottom")
		(1 "F.Mask" user "Board Geometry/Soldermask Top")
		(3 "B.Mask" user "Board Geometry/Soldermask Bottom")
		(17 "Dwgs.User" user "User.Drawings")
		(19 "Cmts.User" user "User.Comments")
		(21 "Eco1.User" user "User.Eco1")
		(23 "Eco2.User" user "User.Eco2")
		(25 "Edge.Cuts" user "Board Geometry/Outline")
		(27 "Margin" user)
		(31 "F.CrtYd" user "Package Geometry/Place Bound Top")
		(29 "B.CrtYd" user "Package Geometry/Place Bound Bottom")
		(35 "F.Fab" user "Ref Des/Assembly Top")
		(33 "B.Fab" user "Ref Des/Assembly Bottom")
	)
	(footprint ""
		(layer "F.Cu")
		(at 17.526 -25.146 180)
		(property "Reference" "R46"
			(at 0.127 4.16433 0)
			(unlocked yes)
			(layer "F.SilkS")
			(effects
				(font
					(size 0.7874 0.5842)
					(thickness 0.1524)
				)
			)
		)
		(property "Value" ""
			(at 0 0 180)
			(layer "F.Fab")
			(effects
				(font
					(size 1.27 1.27)
				)
			)
		)
		(duplicate_pad_numbers_are_jumpers no)
		(fp_line
			(start 0.7874 0.4064)
			(end -0.7874 0.4064)
			(stroke
				(width 0.1524)
				(type default)
			)
			(layer "F.SilkS")
		)
		(fp_line
			(start 0.7874 -0.4064)
			(end 0.7874 0.4064)
			(stroke
				(width 0.1524)
				(type default)
			)
			(layer "F.SilkS")
		)
		(fp_line
			(start -0.7874 0.4064)
			(end -0.7874 -0.4064)
			(stroke
				(width 0.1524)
				(type default)
			)
			(layer "F.SilkS")
		)
		(fp_line
			(start -0.7874 -0.4064)
			(end 0.7874 -0.4064)
			(stroke
				(width 0.1524)
				(type default)
			)
			(layer "F.SilkS")
		)
		(fp_line
			(start 0.67945 0.3048)
			(end 0.120396 0.3048)
			(stroke
				(width 0.1)
				(type default)
			)
			(layer "F.Fab")
		)
		(fp_line
			(start 0.67945 -0.3048)
			(end 0.67945 0.3048)
			(stroke
				(width 0.1)
				(type default)
			)
			(layer "F.Fab")
		)
		(fp_line
			(start 0.12065 -0.2794)
			(end 0.12065 -0.3048)
			(stroke
				(width 0.1)
				(type default)
			)
			(layer "F.Fab")
		)
		(fp_line
			(start 0.12065 -0.3048)
			(end 0.67945 -0.3048)
			(stroke
				(width 0.1)
				(type default)
			)
			(layer "F.Fab")
		)
		(fp_line
			(start 0.120396 0.3048)
			(end 0.120396 0.2794)
			(stroke
				(width 0.1)
				(type default)
			)
			(layer "F.Fab")
		)
		(fp_line
			(start 0.120396 0.2794)
			(end -0.12065 0.2794)
			(stroke
				(width 0.1)
				(type default)
			)
			(layer "F.Fab")
		)
		(fp_line
			(start -0.12065 0.3048)
			(end -0.67945 0.3048)
			(stroke
				(width 0.1)
				(type default)
			)
			(layer "F.Fab")
		)
		(fp_line
			(start -0.12065 0.2794)
			(end -0.12065 0.3048)
			(stroke
				(width 0.1)
				(type default)
			)
			(layer "F.Fab")
		)
		(fp_line
			(start -0.12065 -0.2794)
			(end 0.12065 -0.2794)
			(stroke
				(width 0.1)
				(type default)
			)
			(layer "F.Fab")
		)
		(fp_line
			(start -0.12065 -0.305054)
			(end -0.12065 -0.2794)
			(stroke
				(width 0.1)
				(type default)
			)
			(layer "F.Fab")
		)
		(fp_line
			(start -0.67945 0.3048)
			(end -0.67945 -0.305054)
			(stroke
				(width 0.1)
				(type default)
			)
			(layer "F.Fab")
		)
		(fp_line
			(start -0.67945 -0.305054)
			(end -0.12065 -0.305054)
			(stroke
				(width 0.1)
				(type default)
			)
			(layer "F.Fab")
		)
		(pad "1" smd circle
			(at -0.40005 0 180)
			(size 0 0)
			(layers "F.Cu" "F.Mask" "F.Paste")
			(net "P3V3_STBY")
		)
		(pad "2" smd circle
			(at 0.40005 0 180)
			(size 0 0)
			(layers "F.Cu" "F.Mask" "F.Paste")
			(net "SMB_IO_DEBUG_CARD_SDA")
		)
	)
	(footprint ""
		(layer "F.Cu")
		(at 16.234918 -12.026392)
		(property "Reference" "U1"
			(at -2.772918 2.528062 0)
			(unlocked yes)
			(layer "F.SilkS")
			(effects
				(font
					(size 0.7874 0.5842)
					(thickness 0.1524)
				)
			)
		)
		(property "Value" ""
			(at 0 0 0)
			(layer "F.Fab")
			(effects
				(font
					(size 1.27 1.27)
				)
			)
		)
		(duplicate_pad_numbers_are_jumpers no)
		(fp_line
			(start -1.949958 -1.610106)
			(end 1.949958 -1.610106)
			(stroke
				(width 0.1524)
				(type default)
			)
			(layer "F.SilkS")
		)
		(fp_line
			(start -1.949958 1.610106)
			(end -1.949958 -1.610106)
			(stroke
				(width 0.1524)
				(type default)
			)
			(layer "F.SilkS")
		)
		(fp_line
			(start 1.949958 -1.560068)
			(end 1.949958 1.610106)
			(stroke
				(width 0.1524)
				(type default)
			)
			(layer "F.SilkS")
		)
		(fp_line
			(start 1.949958 1.610106)
			(end -1.949958 1.610106)
			(stroke
				(width 0.1524)
				(type default)
			)
			(layer "F.SilkS")
		)
		(fp_line
			(start -0.750062 -1.560068)
			(end 0.750062 -1.560068)
			(stroke
				(width 0.1)
				(type default)
			)
			(layer "F.Fab")
		)
		(fp_line
			(start -0.750062 1.560068)
			(end -0.750062 -1.560068)
			(stroke
				(width 0.1)
				(type default)
			)
			(layer "F.Fab")
		)
		(fp_line
			(start 0.750062 -1.560068)
			(end 0.750062 1.560068)
			(stroke
				(width 0.1)
				(type default)
			)
			(layer "F.Fab")
		)
		(fp_line
			(start 0.750062 1.560068)
			(end -0.750062 1.560068)
			(stroke
				(width 0.1)
				(type default)
			)
			(layer "F.Fab")
		)
		(pad "D" smd rect
			(at 1.100074 0 270)
			(size 1.016 1.4224)
			(layers "F.Cu" "F.Mask" "F.Paste")
			(net "FM_PFR_LED_AMBER_R")
		)
		(pad "G" smd rect
			(at -1.100074 -0.94996 270)
			(size 1.016 1.4224)
			(layers "F.Cu" "F.Mask" "F.Paste")
			(net "FM_PFR_LED_AMBER_R_N")
		)
		(pad "S" smd rect
			(at -1.100074 0.94996 270)
			(size 1.016 1.4224)
			(layers "F.Cu" "F.Mask" "F.Paste")
			(net "GND")
		)
	)
	(footprint ""
		(layer "F.Cu")
		(at 18.415 -58.801)
		(property "Reference" "R20"
			(at 3.81 0.02667 0)
			(unlocked yes)
			(layer "F.SilkS")
			(effects
				(font
					(size 0.7874 0.5842)
					(thickness 0.1524)
				)
			)
		)
		(property "Value" ""
			(at 0 0 0)
			(layer "F.Fab")
			(effects
				(font
					(size 1.27 1.27)
				)
			)
		)
		(duplicate_pad_numbers_are_jumpers no)
		(fp_line
			(start -0.7874 -0.4064)
			(end 0.7874 -0.4064)
			(stroke
				(width 0.1524)
				(type default)
			)
			(layer "F.SilkS")
		)
		(fp_line
			(start -0.7874 0.4064)
			(end -0.7874 -0.4064)
			(stroke
				(width 0.1524)
				(type default)
			)
			(layer "F.SilkS")
		)
		(fp_line
			(start 0.7874 -0.4064)
			(end 0.7874 0.4064)
			(stroke
				(width 0.1524)
				(type default)
			)
			(layer "F.SilkS")
		)
		(fp_line
			(start 0.7874 0.4064)
			(end -0.7874 0.4064)
			(stroke
				(width 0.1524)
				(type default)
			)
			(layer "F.SilkS")
		)
		(fp_line
			(start -0.67945 -0.305054)
			(end -0.12065 -0.305054)
			(stroke
				(width 0.1)
				(type default)
			)
			(layer "F.Fab")
		)
		(fp_line
			(start -0.67945 0.3048)
			(end -0.67945 -0.305054)
			(stroke
				(width 0.1)
				(type default)
			)
			(layer "F.Fab")
		)
		(fp_line
			(start -0.12065 -0.305054)
			(end -0.12065 -0.2794)
			(stroke
				(width 0.1)
				(type default)
			)
			(layer "F.Fab")
		)
		(fp_line
			(start -0.12065 -0.2794)
			(end 0.12065 -0.2794)
			(stroke
				(width 0.1)
				(type default)
			)
			(layer "F.Fab")
		)
		(fp_line
			(start -0.12065 0.2794)
			(end -0.12065 0.3048)
			(stroke
				(width 0.1)
				(type default)
			)
			(layer "F.Fab")
		)
		(fp_line
			(start -0.12065 0.3048)
			(end -0.67945 0.3048)
			(stroke
				(width 0.1)
				(type default)
			)
			(layer "F.Fab")
		)
		(fp_line
			(start 0.120396 0.2794)
			(end -0.12065 0.2794)
			(stroke
				(width 0.1)
				(type default)
			)
			(layer "F.Fab")
		)
		(fp_line
			(start 0.120396 0.3048)
			(end 0.120396 0.2794)
			(stroke
				(width 0.1)
				(type default)
			)
			(layer "F.Fab")
		)
		(fp_line
			(start 0.12065 -0.3048)
			(end 0.67945 -0.3048)
			(stroke
				(width 0.1)
				(type default)
			)
			(layer "F.Fab")
		)
		(fp_line
			(start 0.12065 -0.2794)
			(end 0.12065 -0.3048)
			(stroke
				(width 0.1)
				(type default)
			)
			(layer "F.Fab")
		)
		(fp_line
			(start 0.67945 -0.3048)
			(end 0.67945 0.3048)
			(stroke
				(width 0.1)
				(type default)
			)
			(layer "F.Fab")
		)
		(fp_line
			(start 0.67945 0.3048)
			(end 0.120396 0.3048)
			(stroke
				(width 0.1)
				(type default)
			)
			(layer "F.Fab")
		)
		(pad "1" smd circle
			(at -0.40005 0)
			(size 0 0)
			(layers "F.Cu" "F.Mask" "F.Paste")
			(net "PCA9539_A0")
		)
		(pad "2" smd circle
			(at 0.40005 0)
			(size 0 0)
			(layers "F.Cu" "F.Mask" "F.Paste")
			(net "P3V3_STBY")
		)
	)
	(footprint ""
		(layer "F.Cu")
		(at 13.462 -22.225 180)
		(property "Reference" "R50"
			(at 2.032 -0.02667 0)
			(unlocked yes)
			(layer "F.SilkS")
			(effects
				(font
					(size 0.7874 0.5842)
					(thickness 0.1524)
				)
			)
		)
		(property "Value" ""
			(at 0 0 180)
			(layer "F.Fab")
			(effects
				(font
					(size 1.27 1.27)
				)
			)
		)
		(duplicate_pad_numbers_are_jumpers no)
		(fp_line
			(start 0.7874 0.4064)
			(end -0.7874 0.4064)
			(stroke
				(width 0.1524)
				(type default)
			)
			(layer "F.SilkS")
		)
		(fp_line
			(start 0.7874 -0.4064)
			(end 0.7874 0.4064)
			(stroke
				(width 0.1524)
				(type default)
			)
			(layer "F.SilkS")
		)
		(fp_line
			(start -0.7874 0.4064)
			(end -0.7874 -0.4064)
			(stroke
				(width 0.1524)
				(type default)
			)
			(layer "F.SilkS")
		)
		(fp_line
			(start -0.7874 -0.4064)
			(end 0.7874 -0.4064)
			(stroke
				(width 0.1524)
				(type default)
			)
			(layer "F.SilkS")
		)
		(fp_line
			(start 0.67945 0.3048)
			(end 0.120396 0.3048)
			(stroke
				(width 0.1)
				(type default)
			)
			(layer "F.Fab")
		)
		(fp_line
			(start 0.67945 -0.3048)
			(end 0.67945 0.3048)
			(stroke
				(width 0.1)
				(type default)
			)
			(layer "F.Fab")
		)
		(fp_line
			(start 0.12065 -0.2794)
			(end 0.12065 -0.3048)
			(stroke
				(width 0.1)
				(type default)
			)
			(layer "F.Fab")
		)
		(fp_line
			(start 0.12065 -0.3048)
			(end 0.67945 -0.3048)
			(stroke
				(width 0.1)
				(type default)
			)
			(layer "F.Fab")
		)
		(fp_line
			(start 0.120396 0.3048)
			(end 0.120396 0.2794)
			(stroke
				(width 0.1)
				(type default)
			)
			(layer "F.Fab")
		)
		(fp_line
			(start 0.120396 0.2794)
			(end -0.12065 0.2794)
			(stroke
				(width 0.1)
				(type default)
			)
			(layer "F.Fab")
		)
		(fp_line
			(start -0.12065 0.3048)
			(end -0.67945 0.3048)
			(stroke
				(width 0.1)
				(type default)
			)
			(layer "F.Fab")
		)
		(fp_line
			(start -0.12065 0.2794)
			(end -0.12065 0.3048)
			(stroke
				(width 0.1)
				(type default)
			)
			(layer "F.Fab")
		)
		(fp_line
			(start -0.12065 -0.2794)
			(end 0.12065 -0.2794)
			(stroke
				(width 0.1)
				(type default)
			)
			(layer "F.Fab")
		)
		(fp_line
			(start -0.12065 -0.305054)
			(end -0.12065 -0.2794)
			(stroke
				(width 0.1)
				(type default)
			)
			(layer "F.Fab")
		)
		(fp_line
			(start -0.67945 0.3048)
			(end -0.67945 -0.305054)
			(stroke
				(width 0.1)
				(type default)
			)
			(layer "F.Fab")
		)
		(fp_line
			(start -0.67945 -0.305054)
			(end -0.12065 -0.305054)
			(stroke
				(width 0.1)
				(type default)
			)
			(layer "F.Fab")
		)
		(pad "1" smd circle
			(at -0.40005 0 180)
			(size 0 0)
			(layers "F.Cu" "F.Mask" "F.Paste")
			(net "PRSNT_DBV2_USB")
		)
		(pad "2" smd circle
			(at 0.40005 0 180)
			(size 0 0)
			(layers "F.Cu" "F.Mask" "F.Paste")
			(net "GND")
		)
	)
	(footprint ""
		(layer "F.Cu")
		(at 8.619998 -5.100066)
		(property "Reference" "D3"
			(at 1.921002 -2.64922 0)
			(unlocked yes)
			(layer "F.SilkS")
			(effects
				(font
					(size 0.7874 0.5842)
					(thickness 0.1524)
				)
				(justify left)
			)
		)
		(property "Value" ""
			(at 0 0 0)
			(layer "F.Fab")
			(effects
				(font
					(size 1.27 1.27)
				)
			)
		)
		(duplicate_pad_numbers_are_jumpers no)
		(fp_line
			(start -1.080008 -1.999996)
			(end 3.620008 -1.999996)
			(stroke
				(width 0.1524)
				(type default)
			)
			(layer "F.SilkS")
		)
		(fp_line
			(start -1.080008 3.999992)
			(end -1.080008 -1.999996)
			(stroke
				(width 0.1524)
				(type default)
			)
			(layer "F.SilkS")
		)
		(fp_line
			(start -0.230124 3.999992)
			(end -1.080008 3.999992)
			(stroke
				(width 0.1524)
				(type default)
			)
			(layer "F.SilkS")
		)
		(fp_line
			(start -0.230124 5.199888)
			(end -0.230124 3.999992)
			(stroke
				(width 0.1524)
				(type default)
			)
			(layer "F.SilkS")
		)
		(fp_line
			(start 2.770124 3.999992)
			(end 2.770124 5.199888)
			(stroke
				(width 0.1524)
				(type default)
			)
			(layer "F.SilkS")
		)
		(fp_line
			(start 3.620008 -1.999996)
			(end 3.620008 3.999992)
			(stroke
				(width 0.1524)
				(type default)
			)
			(layer "F.SilkS")
		)
		(fp_line
			(start 3.620008 3.999992)
			(end 2.770124 3.999992)
			(stroke
				(width 0.1524)
				(type default)
			)
			(layer "F.SilkS")
		)
		(fp_arc
			(start 1.27 6.700012)
			(mid 0.209252 6.260636)
			(end -0.230124 5.199888)
			(stroke
				(width 0.1524)
				(type default)
			)
			(layer "F.SilkS")
		)
		(fp_arc
			(start 2.770124 5.199888)
			(mid 2.330748 6.260636)
			(end 1.27 6.700012)
			(stroke
				(width 0.1524)
				(type default)
			)
			(layer "F.SilkS")
		)
		(fp_line
			(start -1.080008 -1.999996)
			(end 3.620008 -1.999996)
			(stroke
				(width 0.1)
				(type default)
			)
			(layer "F.Fab")
		)
		(fp_line
			(start -1.080008 3.999992)
			(end -1.080008 -1.999996)
			(stroke
				(width 0.1)
				(type default)
			)
			(layer "F.Fab")
		)
		(fp_line
			(start -0.230124 3.999992)
			(end -1.080008 3.999992)
			(stroke
				(width 0.1)
				(type default)
			)
			(layer "F.Fab")
		)
		(fp_line
			(start -0.230124 5.199888)
			(end -0.230124 3.999992)
			(stroke
				(width 0.1)
				(type default)
			)
			(layer "F.Fab")
		)
		(fp_line
			(start 2.770124 3.999992)
			(end 2.770124 5.199888)
			(stroke
				(width 0.1)
				(type default)
			)
			(layer "F.Fab")
		)
		(fp_line
			(start 3.620008 -1.999996)
			(end 3.620008 3.999992)
			(stroke
				(width 0.1)
				(type default)
			)
			(layer "F.Fab")
		)
		(fp_line
			(start 3.620008 3.999992)
			(end 2.770124 3.999992)
			(stroke
				(width 0.1)
				(type default)
			)
			(layer "F.Fab")
		)
		(fp_arc
			(start 1.27 6.700012)
			(mid 0.209252 6.260636)
			(end -0.230124 5.199888)
			(stroke
				(width 0.1)
				(type default)
			)
			(layer "F.Fab")
		)
		(fp_arc
			(start 2.770124 5.199888)
			(mid 2.330748 6.260636)
			(end 1.27 6.700012)
			(stroke
				(width 0.1)
				(type default)
			)
			(layer "F.Fab")
		)
		(pad "A" thru_hole rect
			(at 0 0)
			(size 1.2192 1.2192)
			(drill 0.8128)
			(layers "*.Cu" "*.Mask")
			(remove_unused_layers no)
			(net "P5V_STBY")
			(clearance 0.0508)
			(thermal_gap 0.0508)
			(padstack
				(mode front_inner_back)
				(layer "Inner"
					(shape circle)
					(size 1.2192 1.2192)
					(clearance 0.0508)
				)
				(layer "B.Cu"
					(shape rect)
					(size 1.2192 1.2192)
					(clearance 0.0508)
				)
			)
		)
		(pad "C" thru_hole circle
			(at 2.54 0)
			(size 1.2192 1.2192)
			(drill 0.8128)
			(layers "*.Cu" "*.Mask")
			(remove_unused_layers no)
			(net "PWR_LED_R2_N")
			(clearance 0.0508)
			(thermal_gap 0.0508)
		)
	)
	(footprint ""
		(layer "F.Cu")
		(at 5.715 -25.654)
		(property "Reference" "U3"
			(at -0.762 1.93167 0)
			(unlocked yes)
			(layer "F.SilkS")
			(effects
				(font
					(size 0.7874 0.5842)
					(thickness 0.1524)
				)
				(justify left)
			)
		)
		(property "Value" ""
			(at 0 0 0)
			(layer "F.Fab")
			(effects
				(font
					(size 1.27 1.27)
				)
			)
		)
		(duplicate_pad_numbers_are_jumpers no)
		(fp_line
			(start -1.335278 -1.100074)
			(end -1.335278 1.100074)
			(stroke
				(width 0.1524)
				(type default)
			)
			(layer "F.SilkS")
		)
		(fp_line
			(start -1.335278 1.100074)
			(end 1.335278 1.100074)
			(stroke
				(width 0.1524)
				(type default)
			)
			(layer "F.SilkS")
		)
		(fp_line
			(start 1.335278 -1.100074)
			(end -1.335278 -1.100074)
			(stroke
				(width 0.1524)
				(type default)
			)
			(layer "F.SilkS")
		)
		(fp_line
			(start 1.335278 1.100074)
			(end 1.335278 -1.100074)
			(stroke
				(width 0.1524)
				(type default)
			)
			(layer "F.SilkS")
		)
		(fp_line
			(start -0.674878 -1.100074)
			(end -0.674878 1.100074)
			(stroke
				(width 0.1)
				(type default)
			)
			(layer "F.Fab")
		)
		(fp_line
			(start -0.674878 1.100074)
			(end 0.674878 1.100074)
			(stroke
				(width 0.1)
				(type default)
			)
			(layer "F.Fab")
		)
		(fp_line
			(start 0.674878 -1.100074)
			(end -0.674878 -1.100074)
			(stroke
				(width 0.1)
				(type default)
			)
			(layer "F.Fab")
		)
		(fp_line
			(start 0.674878 1.100074)
			(end 0.674878 -1.100074)
			(stroke
				(width 0.1)
				(type default)
			)
			(layer "F.Fab")
		)
		(pad "D" smd rect
			(at 0.8001 0 270)
			(size 0.6096 0.8128)
			(layers "F.Cu" "F.Mask" "F.Paste")
			(net "SYSTEM_FAULT_ID_LED_R1_N")
		)
		(pad "G" smd rect
			(at -0.8001 -0.649986 270)
			(size 0.6096 0.8128)
			(layers "F.Cu" "F.Mask" "F.Paste")
			(net "SYSTEM_FAULT_ID_LED_R1")
		)
		(pad "S" smd rect
			(at -0.8001 0.649986 270)
			(size 0.6096 0.8128)
			(layers "F.Cu" "F.Mask" "F.Paste")
			(net "GND")
		)
	)
)
